(kicad_pcb
	(version 20260206)
	(generator "pcbnew")
	(generator_version "10.0")
	(general
		(thickness 1.6)
		(legacy_teardrops no)
	)
	(paper "A4")
	(title_block
		(title "v2-pdb — ms_pdb_v2.brd")
		(comment 1 "Open CloudServer (Microsoft) / footprint 337 of 348 (J18), pads 1-46 of 46")
	)
	(layers
		(0 "F.Cu" signal "TOP")
		(4 "In1.Cu" signal "GND")
		(6 "In2.Cu" signal "IN1")
		(8 "In3.Cu" signal "VCC")
		(10 "In4.Cu" signal "VCC1")
		(12 "In5.Cu" signal "IN2")
		(14 "In6.Cu" signal "GND1")
		(2 "B.Cu" signal "BOTTOM")
		(9 "F.Adhes" user "F.Adhesive")
		(11 "B.Adhes" user "B.Adhesive")
		(13 "F.Paste" user "Package Geometry/Pastemask Top")
		(15 "B.Paste" user "Package Geometry/Pastemask Bottom")
		(5 "F.SilkS" user "Ref Des/Silkscreen Top")
		(7 "B.SilkS" user "Ref Des/Silkscreen Bottom")
		(1 "F.Mask" user "Board Geometry/Soldermask Top")
		(3 "B.Mask" user "Board Geometry/Soldermask Bottom")
		(17 "Dwgs.User" user "User.Drawings")
		(19 "Cmts.User" user "User.Comments")
		(21 "Eco1.User" user "User.Eco1")
		(23 "Eco2.User" user "User.Eco2")
		(25 "Edge.Cuts" user "Board Geometry/Outline")
		(27 "Margin" user)
		(31 "F.CrtYd" user "Package Geometry/Place Bound Top")
		(29 "B.CrtYd" user "Package Geometry/Place Bound Bottom")
		(35 "F.Fab" user "Ref Des/Assembly Top")
		(33 "B.Fab" user "Ref Des/Assembly Bottom")
	)
	(footprint ""
		(layer "B.Cu")
		(at 44.03979 -497.21008 90)
		(property "Reference" "J18"
			(at 6.695948 -2.740406 0)
			(unlocked yes)
			(layer "B.SilkS")
			(effects
				(font
					(size 0.7874 0.5842)
					(thickness 0.1524)
				)
				(justify left mirror)
			)
		)
		(property "Value" ""
			(at 0 0 90)
			(layer "B.Fab")
			(effects
				(font
					(size 1.27 1.27)
				)
				(justify mirror)
			)
		)
		(duplicate_pad_numbers_are_jumpers no)
		(pad "" np_thru_hole circle
			(at -1.35001 -2.54)
			(size 2.5146 2.5146)
			(drill 2.5146)
			(layers "*.Cu" "*.Mask")
			(clearance 0.381)
			(thermal_gap 0.381)
		)
		(pad "" np_thru_hole circle
			(at 0 50.8)
			(size 2.5146 2.5146)
			(drill 2.5146)
			(layers "*.Cu" "*.Mask")
			(clearance 0.381)
			(thermal_gap 0.381)
		)
		(pad "P1" thru_hole rect
			(at 0 0)
			(size 1.1684 1.1684)
			(drill 0.762)
			(layers "*.Cu" "*.Mask")
			(remove_unused_layers no)
			(net "GND")
			(clearance 0.0508)
			(padstack
				(mode front_inner_back)
				(layer "Inner"
					(shape circle)
					(size 1.1684 1.1684)
					(clearance 0.0508)
				)
				(layer "B.Cu"
					(shape rect)
					(size 1.1684 1.1684)
					(thermal_gap 0.0508)
					(clearance 0.0508)
				)
			)
		)
		(pad "P2" thru_hole circle
			(at 0 2.54)
			(size 1.1684 1.1684)
			(drill 0.762)
			(layers "*.Cu" "*.Mask")
			(remove_unused_layers no)
			(net "GND")
			(clearance 0.0508)
			(thermal_gap 0.0508)
		)
		(pad "P3" thru_hole circle
			(at 0 5.08)
			(size 1.1684 1.1684)
			(drill 0.762)
			(layers "*.Cu" "*.Mask")
			(remove_unused_layers no)
			(net "GND")
			(clearance 0.0508)
			(thermal_gap 0.0508)
		)
		(pad "P4" thru_hole circle
			(at 0 7.62)
			(size 1.1684 1.1684)
			(drill 0.762)
			(layers "*.Cu" "*.Mask")
			(remove_unused_layers no)
			(net "GND")
			(clearance 0.0508)
			(thermal_gap 0.0508)
		)
		(pad "P5" thru_hole circle
			(at 0 10.16)
			(size 1.1684 1.1684)
			(drill 0.762)
			(layers "*.Cu" "*.Mask")
			(remove_unused_layers no)
			(net "GND")
			(clearance 0.0508)
			(thermal_gap 0.0508)
		)
		(pad "P6" thru_hole circle
			(at 0 12.7)
			(size 1.1684 1.1684)
			(drill 0.762)
			(layers "*.Cu" "*.Mask")
			(remove_unused_layers no)
			(net "GND")
			(clearance 0.0508)
			(thermal_gap 0.0508)
		)
		(pad "P7" thru_hole circle
			(at 0 15.24)
			(size 1.1684 1.1684)
			(drill 0.762)
			(layers "*.Cu" "*.Mask")
			(remove_unused_layers no)
			(net "GND")
			(clearance 0.0508)
			(thermal_gap 0.0508)
		)
		(pad "P8" thru_hole circle
			(at 0 17.78)
			(size 1.1684 1.1684)
			(drill 0.762)
			(layers "*.Cu" "*.Mask")
			(remove_unused_layers no)
			(net "GND")
			(clearance 0.0508)
			(thermal_gap 0.0508)
		)
		(pad "P9" thru_hole circle
			(at 0 20.32)
			(size 1.1684 1.1684)
			(drill 0.762)
			(layers "*.Cu" "*.Mask")
			(remove_unused_layers no)
			(net "P12V")
			(clearance 0.0508)
			(thermal_gap 0.0508)
		)
		(pad "P10" thru_hole circle
			(at 0 22.86)
			(size 1.1684 1.1684)
			(drill 0.762)
			(layers "*.Cu" "*.Mask")
			(remove_unused_layers no)
			(net "P12V")
			(clearance 0.0508)
			(thermal_gap 0.0508)
		)
		(pad "P11" thru_hole circle
			(at 0 25.4)
			(size 1.1684 1.1684)
			(drill 0.762)
			(layers "*.Cu" "*.Mask")
			(remove_unused_layers no)
			(net "P12V")
			(clearance 0.0508)
			(thermal_gap 0.0508)
		)
		(pad "P12" thru_hole circle
			(at 0 27.94)
			(size 1.1684 1.1684)
			(drill 0.762)
			(layers "*.Cu" "*.Mask")
			(remove_unused_layers no)
			(net "P12V")
			(clearance 0.0508)
			(thermal_gap 0.0508)
		)
		(pad "P13" thru_hole circle
			(at 0 30.48)
			(size 1.1684 1.1684)
			(drill 0.762)
			(layers "*.Cu" "*.Mask")
			(remove_unused_layers no)
			(net "P12V")
			(clearance 0.0508)
			(thermal_gap 0.0508)
		)
		(pad "P14" thru_hole circle
			(at 0 33.02)
			(size 1.1684 1.1684)
			(drill 0.762)
			(layers "*.Cu" "*.Mask")
			(remove_unused_layers no)
			(net "P12V")
			(clearance 0.0508)
			(thermal_gap 0.0508)
		)
		(pad "P15" thru_hole circle
			(at 0 35.56)
			(size 1.1684 1.1684)
			(drill 0.762)
			(layers "*.Cu" "*.Mask")
			(remove_unused_layers no)
			(net "P12V")
			(clearance 0.0508)
			(thermal_gap 0.0508)
		)
		(pad "P16" thru_hole circle
			(at 0 38.1)
			(size 1.1684 1.1684)
			(drill 0.762)
			(layers "*.Cu" "*.Mask")
			(remove_unused_layers no)
			(net "P12V")
			(clearance 0.0508)
			(thermal_gap 0.0508)
		)
		(pad "P17" thru_hole circle
			(at -2.70002 38.1)
			(size 1.1684 1.1684)
			(drill 0.762)
			(layers "*.Cu" "*.Mask")
			(remove_unused_layers no)
			(net "P12V")
			(clearance 0.0508)
			(thermal_gap 0.0508)
		)
		(pad "P18" thru_hole circle
			(at -2.70002 35.56)
			(size 1.1684 1.1684)
			(drill 0.762)
			(layers "*.Cu" "*.Mask")
			(remove_unused_layers no)
			(net "P12V")
			(clearance 0.0508)
			(thermal_gap 0.0508)
		)
		(pad "P19" thru_hole circle
			(at -2.70002 33.02)
			(size 1.1684 1.1684)
			(drill 0.762)
			(layers "*.Cu" "*.Mask")
			(remove_unused_layers no)
			(net "P12V")
			(clearance 0.0508)
			(thermal_gap 0.0508)
		)
		(pad "P20" thru_hole circle
			(at -2.70002 30.48)
			(size 1.1684 1.1684)
			(drill 0.762)
			(layers "*.Cu" "*.Mask")
			(remove_unused_layers no)
			(net "P12V")
			(clearance 0.0508)
			(thermal_gap 0.0508)
		)
		(pad "P21" thru_hole circle
			(at -2.70002 27.94)
			(size 1.1684 1.1684)
			(drill 0.762)
			(layers "*.Cu" "*.Mask")
			(remove_unused_layers no)
			(net "P12V")
			(clearance 0.0508)
			(thermal_gap 0.0508)
		)
		(pad "P22" thru_hole circle
			(at -2.70002 25.4)
			(size 1.1684 1.1684)
			(drill 0.762)
			(layers "*.Cu" "*.Mask")
			(remove_unused_layers no)
			(net "P12V")
			(clearance 0.0508)
			(thermal_gap 0.0508)
		)
		(pad "P23" thru_hole circle
			(at -2.70002 22.86)
			(size 1.1684 1.1684)
			(drill 0.762)
			(layers "*.Cu" "*.Mask")
			(remove_unused_layers no)
			(net "P12V")
			(clearance 0.0508)
			(thermal_gap 0.0508)
		)
		(pad "P24" thru_hole circle
			(at -2.70002 20.32)
			(size 1.1684 1.1684)
			(drill 0.762)
			(layers "*.Cu" "*.Mask")
			(remove_unused_layers no)
			(net "P12V")
			(clearance 0.0508)
			(thermal_gap 0.0508)
		)
		(pad "P25" thru_hole circle
			(at -2.70002 17.78)
			(size 1.1684 1.1684)
			(drill 0.762)
			(layers "*.Cu" "*.Mask")
			(remove_unused_layers no)
			(net "GND")
			(clearance 0.0508)
			(thermal_gap 0.0508)
		)
		(pad "P26" thru_hole circle
			(at -2.70002 15.24)
			(size 1.1684 1.1684)
			(drill 0.762)
			(layers "*.Cu" "*.Mask")
			(remove_unused_layers no)
			(net "GND")
			(clearance 0.0508)
			(thermal_gap 0.0508)
		)
		(pad "P27" thru_hole circle
			(at -2.70002 12.7)
			(size 1.1684 1.1684)
			(drill 0.762)
			(layers "*.Cu" "*.Mask")
			(remove_unused_layers no)
			(net "GND")
			(clearance 0.0508)
			(thermal_gap 0.0508)
		)
		(pad "P28" thru_hole circle
			(at -2.70002 10.16)
			(size 1.1684 1.1684)
			(drill 0.762)
			(layers "*.Cu" "*.Mask")
			(remove_unused_layers no)
			(net "GND")
			(clearance 0.0508)
			(thermal_gap 0.0508)
		)
		(pad "P29" thru_hole circle
			(at -2.70002 7.62)
			(size 1.1684 1.1684)
			(drill 0.762)
			(layers "*.Cu" "*.Mask")
			(remove_unused_layers no)
			(net "GND")
			(clearance 0.0508)
			(thermal_gap 0.0508)
		)
		(pad "P30" thru_hole circle
			(at -2.70002 5.08)
			(size 1.1684 1.1684)
			(drill 0.762)
			(layers "*.Cu" "*.Mask")
			(remove_unused_layers no)
			(net "GND")
			(clearance 0.0508)
			(thermal_gap 0.0508)
		)
		(pad "P31" thru_hole circle
			(at -2.70002 2.54)
			(size 1.1684 1.1684)
			(drill 0.762)
			(layers "*.Cu" "*.Mask")
			(remove_unused_layers no)
			(net "GND")
			(clearance 0.0508)
			(thermal_gap 0.0508)
		)
		(pad "P32" thru_hole circle
			(at -2.70002 0)
			(size 1.1684 1.1684)
			(drill 0.762)
			(layers "*.Cu" "*.Mask")
			(remove_unused_layers no)
			(net "GND")
			(clearance 0.0508)
			(thermal_gap 0.0508)
		)
		(pad "S1" thru_hole circle
			(at 0.55499 41.60012)
			(size 1.1684 1.1684)
			(drill 0.762)
			(layers "*.Cu" "*.Mask")
			(remove_unused_layers no)
			(net "T12_BLAD1_TXD")
			(clearance 0.0508)
			(thermal_gap 0.0508)
		)
		(pad "S2" thru_hole circle
			(at -0.71501 42.87012)
			(size 1.1684 1.1684)
			(drill 0.762)
			(layers "*.Cu" "*.Mask")
			(remove_unused_layers no)
			(net "T12_BLAD1_RXD")
			(clearance 0.0508)
			(thermal_gap 0.0508)
		)
		(pad "S3" thru_hole circle
			(at 0.55499 44.14012)
			(size 1.1684 1.1684)
			(drill 0.762)
			(layers "*.Cu" "*.Mask")
			(remove_unused_layers no)
			(net "T12_BLAD1_EN")
			(clearance 0.0508)
			(thermal_gap 0.0508)
		)
		(pad "S4" thru_hole circle
			(at -0.71501 45.41012)
			(size 1.1684 1.1684)
			(drill 0.762)
			(layers "*.Cu" "*.Mask")
			(remove_unused_layers no)
			(net "B23_PSU_ALERT_N")
			(clearance 0.0508)
			(thermal_gap 0.0508)
		)
		(pad "S5" thru_hole circle
			(at 0.55499 46.68012)
			(size 1.1684 1.1684)
			(drill 0.762)
			(layers "*.Cu" "*.Mask")
			(remove_unused_layers no)
			(net "T12_BLAD2_TXD")
			(clearance 0.0508)
			(thermal_gap 0.0508)
		)
		(pad "S6" thru_hole circle
			(at -0.71501 47.95012)
			(size 1.1684 1.1684)
			(drill 0.762)
			(layers "*.Cu" "*.Mask")
			(remove_unused_layers no)
			(net "T12_BLAD2_RXD")
			(clearance 0.0508)
			(thermal_gap 0.0508)
		)
		(pad "S7" thru_hole circle
			(at -3.25501 47.95012)
			(size 1.1684 1.1684)
			(drill 0.762)
			(layers "*.Cu" "*.Mask")
			(remove_unused_layers no)
			(net "T12_BLAD4_RXD")
			(clearance 0.0508)
			(thermal_gap 0.0508)
		)
		(pad "S8" thru_hole circle
			(at -1.98501 46.68012)
			(size 1.1684 1.1684)
			(drill 0.762)
			(layers "*.Cu" "*.Mask")
			(remove_unused_layers no)
			(net "T12_BLAD4_TXD")
			(clearance 0.0508)
			(thermal_gap 0.0508)
		)
		(pad "S9" thru_hole circle
			(at -3.25501 45.41012)
			(size 1.1684 1.1684)
			(drill 0.762)
			(layers "*.Cu" "*.Mask")
			(remove_unused_layers no)
			(net "B24_PSU_ALERT_N")
			(clearance 0.0508)
			(thermal_gap 0.0508)
		)
		(pad "S10" thru_hole circle
			(at -1.98501 44.14012)
			(size 1.1684 1.1684)
			(drill 0.762)
			(layers "*.Cu" "*.Mask")
			(remove_unused_layers no)
			(net "T12_BLAD3_EN")
			(clearance 0.0508)
			(thermal_gap 0.0508)
		)
		(pad "S11" thru_hole circle
			(at -3.25501 42.87012)
			(size 1.1684 1.1684)
			(drill 0.762)
			(layers "*.Cu" "*.Mask")
			(remove_unused_layers no)
			(net "T12_BLAD3_RXD")
			(clearance 0.0508)
			(thermal_gap 0.0508)
		)
		(pad "S12" thru_hole circle
			(at -1.98501 41.60012)
			(size 1.1684 1.1684)
			(drill 0.762)
			(layers "*.Cu" "*.Mask")
			(remove_unused_layers no)
			(net "T12_BLAD3_TXD")
			(clearance 0.0508)
			(thermal_gap 0.0508)
		)
	)
)
